(kicad_pcb
	(version 20260206)
	(generator "pcbnew")
	(generator_version "10.0")
	(general
		(thickness 1.6)
		(legacy_teardrops no)
	)
	(paper "A4")
	(title_block
		(title "Wiwynn_Tioga_Pass_MB.brd")
		(comment 1 "Tioga Pass / footprints 1083-1089 of 4770")
	)
	(layers
		(0 "F.Cu" signal "TOP")
		(4 "In1.Cu" signal "L2GND")
		(6 "In2.Cu" signal "L3")
		(8 "In3.Cu" signal "L4GND")
		(10 "In4.Cu" signal "L5")
		(12 "In5.Cu" signal "L6GND")
		(14 "In6.Cu" signal "L7VCC")
		(16 "In7.Cu" signal "L8VCC")
		(18 "In8.Cu" signal "L9GND")
		(20 "In9.Cu" signal "L10")
		(22 "In10.Cu" signal "L11GND")
		(24 "In11.Cu" signal "L12")
		(26 "In12.Cu" signal "L13GND")
		(2 "B.Cu" signal "BOTTOM")
		(9 "F.Adhes" user "F.Adhesive")
		(11 "B.Adhes" user "B.Adhesive")
		(13 "F.Paste" user "Package Geometry/Pastemask Top")
		(15 "B.Paste" user "Package Geometry/Pastemask Bottom")
		(5 "F.SilkS" user "Ref Des/Silkscreen Top")
		(7 "B.SilkS" user "Ref Des/Silkscreen Bottom")
		(1 "F.Mask" user "Board Geometry/Soldermask Top")
		(3 "B.Mask" user "Board Geometry/Soldermask Bottom")
		(17 "Dwgs.User" user "User.Drawings")
		(19 "Cmts.User" user "User.Comments")
		(21 "Eco1.User" user "User.Eco1")
		(23 "Eco2.User" user "User.Eco2")
		(25 "Edge.Cuts" user "Board Geometry/Outline")
		(27 "Margin" user)
		(31 "F.CrtYd" user "Package Geometry/Place Bound Top")
		(29 "B.CrtYd" user "Package Geometry/Place Bound Bottom")
		(35 "F.Fab" user "Ref Des/Assembly Top")
		(33 "B.Fab" user "Ref Des/Assembly Bottom")
	)
	(footprint ""
		(layer "F.Cu")
		(at 431.734468 -50.482246 90)
		(property "Reference" "C9F23"
			(at 0 0 90)
			(layer "F.SilkS")
			(hide yes)
			(effects
				(font
					(size 1.27 1.27)
				)
			)
		)
		(property "Value" ""
			(at 0 0 90)
			(layer "F.Fab")
			(effects
				(font
					(size 1.27 1.27)
				)
			)
		)
		(duplicate_pad_numbers_are_jumpers no)
		(fp_poly
			(pts
				(xy 0.3048 -0.1016) (xy 0.3048 0.9906) (xy -0.3048 0.9906) (xy -0.3048 -0.1016)
			)
			(stroke
				(width 0)
				(type default)
			)
			(fill no)
			(layer "F.CrtYd")
		)
		(fp_line
			(start 0.3048 -0.1016)
			(end -0.3048 -0.1016)
			(stroke
				(width 0.1)
				(type default)
			)
			(layer "F.Fab")
		)
		(fp_line
			(start -0.3048 -0.1016)
			(end -0.3048 0.9906)
			(stroke
				(width 0.1)
				(type default)
			)
			(layer "F.Fab")
		)
		(fp_line
			(start 0.3048 0.9906)
			(end 0.3048 -0.1016)
			(stroke
				(width 0.1)
				(type default)
			)
			(layer "F.Fab")
		)
		(fp_line
			(start -0.3048 0.9906)
			(end 0.3048 0.9906)
			(stroke
				(width 0.1)
				(type default)
			)
			(layer "F.Fab")
		)
		(pad "1" smd rect
			(at 0 0 90)
			(size 0.508 0.508)
			(layers "F.Cu" "F.Mask" "F.Paste")
			(net "P3V3_STBY")
		)
		(pad "2" smd rect
			(at 0 0.889 90)
			(size 0.508 0.508)
			(layers "F.Cu" "F.Mask" "F.Paste")
			(net "GND")
		)
		(zone
			(layer "F.Cu")
			(hatch none 0.5)
			(connect_pads
				(clearance 0)
			)
			(min_thickness 0.25)
			(keepout
				(tracks allowed)
				(vias not_allowed)
				(pads allowed)
				(copperpour not_allowed)
				(footprints allowed)
			)
			(placement
				(enabled no)
				(sheetname "")
			)
			(fill
				(thermal_gap 0.5)
				(thermal_bridge_width 0.5)
				(island_removal_mode 0)
			)
			(polygon
				(pts
					(xy 431.988468 -50.228246) (xy 431.988468 -50.736246) (xy 432.369468 -50.736246) (xy 432.369468 -50.228246)
				)
			)
		)
		(zone
			(layer "F.Cu")
			(hatch none 0.5)
			(connect_pads
				(clearance 0)
			)
			(min_thickness 0.25)
			(keepout
				(tracks not_allowed)
				(vias allowed)
				(pads allowed)
				(copperpour not_allowed)
				(footprints allowed)
			)
			(placement
				(enabled no)
				(sheetname "")
			)
			(fill
				(thermal_gap 0.5)
				(thermal_bridge_width 0.5)
				(island_removal_mode 0)
			)
			(polygon
				(pts
					(xy 432.369468 -50.228246) (xy 432.369468 -50.736246) (xy 431.988468 -50.736246) (xy 431.988468 -50.228246)
				)
			)
		)
	)
	(footprint ""
		(layer "F.Cu")
		(at 409.6512 -114.3 90)
		(property "Reference" "R8B29"
			(at 0 0 90)
			(layer "F.SilkS")
			(hide yes)
			(effects
				(font
					(size 1.27 1.27)
				)
			)
		)
		(property "Value" ""
			(at 0 0 90)
			(layer "F.Fab")
			(effects
				(font
					(size 1.27 1.27)
				)
			)
		)
		(duplicate_pad_numbers_are_jumpers no)
		(fp_poly
			(pts
				(xy -0.2794 -0.1016) (xy 0.2794 -0.1016) (xy 0.2794 0.9906) (xy -0.2794 0.9906)
			)
			(stroke
				(width 0)
				(type default)
			)
			(fill no)
			(layer "F.CrtYd")
		)
		(fp_line
			(start 0.2794 -0.1016)
			(end -0.2794 -0.1016)
			(stroke
				(width 0.1)
				(type default)
			)
			(layer "F.Fab")
		)
		(fp_line
			(start -0.2794 -0.1016)
			(end -0.2794 0.9906)
			(stroke
				(width 0.1)
				(type default)
			)
			(layer "F.Fab")
		)
		(fp_line
			(start 0.2794 0.9906)
			(end 0.2794 -0.1016)
			(stroke
				(width 0.1)
				(type default)
			)
			(layer "F.Fab")
		)
		(fp_line
			(start -0.2794 0.9906)
			(end 0.2794 0.9906)
			(stroke
				(width 0.1)
				(type default)
			)
			(layer "F.Fab")
		)
		(pad "1" smd rect
			(at 0 0 90)
			(size 0.508 0.508)
			(layers "F.Cu" "F.Mask" "F.Paste")
			(net "SGPIO_PCH_SSATA_DOUT0")
		)
		(pad "2" smd rect
			(at 0 0.889 90)
			(size 0.508 0.508)
			(layers "F.Cu" "F.Mask" "F.Paste")
			(net "SGPIO_PCH_SSATA_DOUT0_R")
		)
		(zone
			(layer "F.Cu")
			(hatch none 0.5)
			(connect_pads
				(clearance 0)
			)
			(min_thickness 0.25)
			(keepout
				(tracks allowed)
				(vias not_allowed)
				(pads allowed)
				(copperpour not_allowed)
				(footprints allowed)
			)
			(placement
				(enabled no)
				(sheetname "")
			)
			(fill
				(thermal_gap 0.5)
				(thermal_bridge_width 0.5)
				(island_removal_mode 0)
			)
			(polygon
				(pts
					(xy 409.9052 -114.046) (xy 409.9052 -114.554) (xy 410.2862 -114.554) (xy 410.2862 -114.046)
				)
			)
		)
		(zone
			(layer "F.Cu")
			(hatch none 0.5)
			(connect_pads
				(clearance 0)
			)
			(min_thickness 0.25)
			(keepout
				(tracks not_allowed)
				(vias allowed)
				(pads allowed)
				(copperpour not_allowed)
				(footprints allowed)
			)
			(placement
				(enabled no)
				(sheetname "")
			)
			(fill
				(thermal_gap 0.5)
				(thermal_bridge_width 0.5)
				(island_removal_mode 0)
			)
			(polygon
				(pts
					(xy 410.2862 -114.046) (xy 410.2862 -114.554) (xy 409.9052 -114.554) (xy 409.9052 -114.046)
				)
			)
		)
	)
	(footprint ""
		(layer "F.Cu")
		(at 88.392 -149.8092 90)
		(property "Reference" "C2A4"
			(at 1.848866 0.752348 90)
			(unlocked yes)
			(layer "F.SilkS")
			(effects
				(font
					(size 1.27 0.9652)
					(thickness 0.1524)
				)
			)
		)
		(property "Value" ""
			(at 0 0 90)
			(layer "F.Fab")
			(effects
				(font
					(size 1.27 1.27)
				)
			)
		)
		(duplicate_pad_numbers_are_jumpers no)
		(fp_rect
			(start -0.500126 1.598422)
			(end 0.500126 -0.201422)
			(stroke
				(width 0)
				(type default)
			)
			(fill no)
			(layer "F.CrtYd")
		)
		(fp_line
			(start 0.500126 -0.201422)
			(end 0.500126 1.598422)
			(stroke
				(width 0.1)
				(type default)
			)
			(layer "F.Fab")
		)
		(fp_line
			(start -0.500126 -0.201422)
			(end 0.500126 -0.201422)
			(stroke
				(width 0.1)
				(type default)
			)
			(layer "F.Fab")
		)
		(fp_line
			(start 0.500126 1.598422)
			(end -0.500126 1.598422)
			(stroke
				(width 0.1)
				(type default)
			)
			(layer "F.Fab")
		)
		(fp_line
			(start -0.500126 1.598422)
			(end -0.500126 -0.201422)
			(stroke
				(width 0.1)
				(type default)
			)
			(layer "F.Fab")
		)
		(pad "1" smd rect
			(at 0 0)
			(size 0.889 0.9906)
			(layers "F.Cu" "F.Mask" "F.Paste")
			(net "PVDDQ_KLM")
		)
		(pad "2" smd rect
			(at 0 1.397)
			(size 0.889 0.9906)
			(layers "F.Cu" "F.Mask" "F.Paste")
			(net "GND")
		)
		(zone
			(layer "F.Cu")
			(hatch none 0.5)
			(connect_pads
				(clearance 0)
			)
			(min_thickness 0.25)
			(keepout
				(tracks allowed)
				(vias not_allowed)
				(pads allowed)
				(copperpour not_allowed)
				(footprints allowed)
			)
			(placement
				(enabled no)
				(sheetname "")
			)
			(fill
				(thermal_gap 0.5)
				(thermal_bridge_width 0.5)
				(island_removal_mode 0)
			)
			(polygon
				(pts
					(xy 89.3445 -149.3139) (xy 89.3445 -150.3045) (xy 88.8365 -150.3045) (xy 88.8365 -149.3139)
				)
			)
		)
		(zone
			(layer "F.Cu")
			(hatch none 0.5)
			(connect_pads
				(clearance 0)
			)
			(min_thickness 0.25)
			(keepout
				(tracks not_allowed)
				(vias allowed)
				(pads allowed)
				(copperpour not_allowed)
				(footprints allowed)
			)
			(placement
				(enabled no)
				(sheetname "")
			)
			(fill
				(thermal_gap 0.5)
				(thermal_bridge_width 0.5)
				(island_removal_mode 0)
			)
			(polygon
				(pts
					(xy 89.3445 -149.3139) (xy 89.3445 -150.3045) (xy 88.8365 -150.3045) (xy 88.8365 -149.3139)
				)
			)
		)
	)
	(footprint ""
		(layer "F.Cu")
		(at 0.635 -20.0406 -90)
		(property "Reference" "C1F27"
			(at 0 0 270)
			(layer "F.SilkS")
			(hide yes)
			(effects
				(font
					(size 1.27 1.27)
				)
			)
		)
		(property "Value" ""
			(at 0 0 270)
			(layer "F.Fab")
			(effects
				(font
					(size 1.27 1.27)
				)
			)
		)
		(duplicate_pad_numbers_are_jumpers no)
		(fp_poly
			(pts
				(xy 0.3048 -0.1016) (xy 0.3048 0.9906) (xy -0.3048 0.9906) (xy -0.3048 -0.1016)
			)
			(stroke
				(width 0)
				(type default)
			)
			(fill no)
			(layer "F.CrtYd")
		)
		(fp_line
			(start -0.3048 0.9906)
			(end 0.3048 0.9906)
			(stroke
				(width 0.1)
				(type default)
			)
			(layer "F.Fab")
		)
		(fp_line
			(start 0.3048 0.9906)
			(end 0.3048 -0.1016)
			(stroke
				(width 0.1)
				(type default)
			)
			(layer "F.Fab")
		)
		(fp_line
			(start -0.3048 -0.1016)
			(end -0.3048 0.9906)
			(stroke
				(width 0.1)
				(type default)
			)
			(layer "F.Fab")
		)
		(fp_line
			(start 0.3048 -0.1016)
			(end -0.3048 -0.1016)
			(stroke
				(width 0.1)
				(type default)
			)
			(layer "F.Fab")
		)
		(pad "1" smd rect
			(at 0 0 270)
			(size 0.508 0.508)
			(layers "F.Cu" "F.Mask" "F.Paste")
			(net "VR_FET_SW_P12V_STBY_PVDDQ_GHJ")
		)
		(pad "2" smd rect
			(at 0 0.889 270)
			(size 0.508 0.508)
			(layers "F.Cu" "F.Mask" "F.Paste")
			(net "GND")
		)
		(zone
			(layer "F.Cu")
			(hatch none 0.5)
			(connect_pads
				(clearance 0)
			)
			(min_thickness 0.25)
			(keepout
				(tracks not_allowed)
				(vias allowed)
				(pads allowed)
				(copperpour not_allowed)
				(footprints allowed)
			)
			(placement
				(enabled no)
				(sheetname "")
			)
			(fill
				(thermal_gap 0.5)
				(thermal_bridge_width 0.5)
				(island_removal_mode 0)
			)
			(polygon
				(pts
					(xy 0 -20.2946) (xy 0 -19.7866) (xy 0.381 -19.7866) (xy 0.381 -20.2946)
				)
			)
		)
		(zone
			(layer "F.Cu")
			(hatch none 0.5)
			(connect_pads
				(clearance 0)
			)
			(min_thickness 0.25)
			(keepout
				(tracks allowed)
				(vias not_allowed)
				(pads allowed)
				(copperpour not_allowed)
				(footprints allowed)
			)
			(placement
				(enabled no)
				(sheetname "")
			)
			(fill
				(thermal_gap 0.5)
				(thermal_bridge_width 0.5)
				(island_removal_mode 0)
			)
			(polygon
				(pts
					(xy 0.381 -20.2946) (xy 0.381 -19.7866) (xy 0 -19.7866) (xy 0 -20.2946)
				)
			)
		)
	)
	(footprint ""
		(layer "F.Cu")
		(at 488.6706 -123.75134)
		(property "Reference" "U9B4"
			(at 1.30302 5.01777 0)
			(unlocked yes)
			(layer "F.SilkS")
			(effects
				(font
					(size 0.7874 0.5842)
					(thickness 0.1524)
				)
			)
		)
		(property "Value" ""
			(at 0 0 0)
			(layer "F.Fab")
			(effects
				(font
					(size 1.27 1.27)
				)
			)
		)
		(duplicate_pad_numbers_are_jumpers no)
		(fp_line
			(start 1.566672 -0.52324)
			(end 0.985774 -0.52324)
			(stroke
				(width 0.1524)
				(type default)
			)
			(layer "F.SilkS")
		)
		(fp_line
			(start 1.583436 2.47396)
			(end 0.965454 2.47396)
			(stroke
				(width 0.1524)
				(type default)
			)
			(layer "F.SilkS")
		)
		(fp_circle
			(center -0.635 -0.889)
			(end -0.508 -0.889)
			(stroke
				(width 0.254)
				(type default)
			)
			(fill no)
			(layer "F.SilkS")
		)
		(fp_rect
			(start 0.3937 2.47396)
			(end 2.1463 -0.52324)
			(stroke
				(width 0)
				(type default)
			)
			(fill no)
			(layer "F.CrtYd")
		)
		(fp_line
			(start 0.3937 -0.52324)
			(end 2.1463 -0.52324)
			(stroke
				(width 0.1)
				(type default)
			)
			(layer "F.Fab")
		)
		(fp_line
			(start 0.3937 2.47396)
			(end 0.3937 -0.52324)
			(stroke
				(width 0.1)
				(type default)
			)
			(layer "F.Fab")
		)
		(fp_line
			(start 2.1463 -0.52324)
			(end 2.1463 2.47396)
			(stroke
				(width 0.1)
				(type default)
			)
			(layer "F.Fab")
		)
		(fp_line
			(start 2.1463 2.47396)
			(end 0.3937 2.47396)
			(stroke
				(width 0.1)
				(type default)
			)
			(layer "F.Fab")
		)
		(fp_circle
			(center -0.635 -0.889)
			(end -0.508 -0.889)
			(stroke
				(width 0.254)
				(type default)
			)
			(fill no)
			(layer "F.Fab")
		)
		(pad "1" smd rect
			(at 0 0)
			(size 1.27 0.381)
			(layers "F.Cu" "F.Mask" "F.Paste")
			(net "ISENSE_TMP421_1_DXP")
		)
		(pad "2" smd rect
			(at 0 0.65024)
			(size 1.27 0.381)
			(layers "F.Cu" "F.Mask" "F.Paste")
			(net "ISENSE_TMP421_1_DXN")
		)
		(pad "3" smd rect
			(at 0 1.30048)
			(size 1.27 0.381)
			(layers "F.Cu" "F.Mask" "F.Paste")
			(net "PU_TMP421_1_A1")
		)
		(pad "4" smd rect
			(at 0 1.95072)
			(size 1.27 0.381)
			(layers "F.Cu" "F.Mask" "F.Paste")
			(net "PD_TMP421_1_A0")
		)
		(pad "5" smd rect
			(at 2.54 1.95072)
			(size 1.27 0.381)
			(layers "F.Cu" "F.Mask" "F.Paste")
			(net "GND")
		)
		(pad "6" smd rect
			(at 2.54 1.30048)
			(size 1.27 0.381)
			(layers "F.Cu" "F.Mask" "F.Paste")
			(net "SMB_SENSOR_TMP421_1_SDA")
		)
		(pad "7" smd rect
			(at 2.54 0.65024)
			(size 1.27 0.381)
			(layers "F.Cu" "F.Mask" "F.Paste")
			(net "SMB_SENSOR_TMP421_1_SCL")
		)
		(pad "8" smd rect
			(at 2.54 0)
			(size 1.27 0.381)
			(layers "F.Cu" "F.Mask" "F.Paste")
			(net "P3V3_STBY")
		)
	)
	(footprint ""
		(layer "F.Cu")
		(at 406.146 -46.8249 180)
		(property "Reference" "R2T64"
			(at 0 0 180)
			(layer "F.SilkS")
			(hide yes)
			(effects
				(font
					(size 1.27 1.27)
				)
			)
		)
		(property "Value" ""
			(at 0 0 180)
			(layer "F.Fab")
			(effects
				(font
					(size 1.27 1.27)
				)
			)
		)
		(duplicate_pad_numbers_are_jumpers no)
		(fp_poly
			(pts
				(xy -0.2794 -0.1016) (xy 0.2794 -0.1016) (xy 0.2794 0.9906) (xy -0.2794 0.9906)
			)
			(stroke
				(width 0)
				(type default)
			)
			(fill no)
			(layer "F.CrtYd")
		)
		(fp_line
			(start 0.2794 0.9906)
			(end 0.2794 -0.1016)
			(stroke
				(width 0.1)
				(type default)
			)
			(layer "F.Fab")
		)
		(fp_line
			(start 0.2794 -0.1016)
			(end -0.2794 -0.1016)
			(stroke
				(width 0.1)
				(type default)
			)
			(layer "F.Fab")
		)
		(fp_line
			(start -0.2794 0.9906)
			(end 0.2794 0.9906)
			(stroke
				(width 0.1)
				(type default)
			)
			(layer "F.Fab")
		)
		(fp_line
			(start -0.2794 -0.1016)
			(end -0.2794 0.9906)
			(stroke
				(width 0.1)
				(type default)
			)
			(layer "F.Fab")
		)
		(pad "1" smd rect
			(at 0 0 180)
			(size 0.508 0.508)
			(layers "F.Cu" "F.Mask" "F.Paste")
			(net "FM_CPU_ERR1_LVT3_N")
		)
		(pad "2" smd rect
			(at 0 0.889 180)
			(size 0.508 0.508)
			(layers "F.Cu" "F.Mask" "F.Paste")
			(net "FM_CPU_ERR1_LVT3_BMC_N")
		)
		(zone
			(layer "F.Cu")
			(hatch none 0.5)
			(connect_pads
				(clearance 0)
			)
			(min_thickness 0.25)
			(keepout
				(tracks not_allowed)
				(vias allowed)
				(pads allowed)
				(copperpour not_allowed)
				(footprints allowed)
			)
			(placement
				(enabled no)
				(sheetname "")
			)
			(fill
				(thermal_gap 0.5)
				(thermal_bridge_width 0.5)
				(island_removal_mode 0)
			)
			(polygon
				(pts
					(xy 406.4 -47.4599) (xy 405.892 -47.4599) (xy 405.892 -47.0789) (xy 406.4 -47.0789)
				)
			)
		)
		(zone
			(layer "F.Cu")
			(hatch none 0.5)
			(connect_pads
				(clearance 0)
			)
			(min_thickness 0.25)
			(keepout
				(tracks allowed)
				(vias not_allowed)
				(pads allowed)
				(copperpour not_allowed)
				(footprints allowed)
			)
			(placement
				(enabled no)
				(sheetname "")
			)
			(fill
				(thermal_gap 0.5)
				(thermal_bridge_width 0.5)
				(island_removal_mode 0)
			)
			(polygon
				(pts
					(xy 406.4 -47.0789) (xy 405.892 -47.0789) (xy 405.892 -47.4599) (xy 406.4 -47.4599)
				)
			)
		)
	)
	(footprint ""
		(layer "F.Cu")
		(at 152.146 -25.908 -90)
		(property "Reference" "C3F2"
			(at 0 0 270)
			(layer "F.SilkS")
			(hide yes)
			(effects
				(font
					(size 1.27 1.27)
				)
			)
		)
		(property "Value" ""
			(at 0 0 270)
			(layer "F.Fab")
			(effects
				(font
					(size 1.27 1.27)
				)
			)
		)
		(duplicate_pad_numbers_are_jumpers no)
		(fp_poly
			(pts
				(xy 0.3048 -0.1016) (xy 0.3048 0.9906) (xy -0.3048 0.9906) (xy -0.3048 -0.1016)
			)
			(stroke
				(width 0)
				(type default)
			)
			(fill no)
			(layer "F.CrtYd")
		)
		(fp_line
			(start -0.3048 0.9906)
			(end 0.3048 0.9906)
			(stroke
				(width 0.1)
				(type default)
			)
			(layer "F.Fab")
		)
		(fp_line
			(start 0.3048 0.9906)
			(end 0.3048 -0.1016)
			(stroke
				(width 0.1)
				(type default)
			)
			(layer "F.Fab")
		)
		(fp_line
			(start -0.3048 -0.1016)
			(end -0.3048 0.9906)
			(stroke
				(width 0.1)
				(type default)
			)
			(layer "F.Fab")
		)
		(fp_line
			(start 0.3048 -0.1016)
			(end -0.3048 -0.1016)
			(stroke
				(width 0.1)
				(type default)
			)
			(layer "F.Fab")
		)
		(pad "1" smd rect
			(at 0 0 270)
			(size 0.508 0.508)
			(layers "F.Cu" "F.Mask" "F.Paste")
			(net "P3V3")
		)
		(pad "2" smd rect
			(at 0 0.889 270)
			(size 0.508 0.508)
			(layers "F.Cu" "F.Mask" "F.Paste")
			(net "GND")
		)
		(zone
			(layer "F.Cu")
			(hatch none 0.5)
			(connect_pads
				(clearance 0)
			)
			(min_thickness 0.25)
			(keepout
				(tracks not_allowed)
				(vias allowed)
				(pads allowed)
				(copperpour not_allowed)
				(footprints allowed)
			)
			(placement
				(enabled no)
				(sheetname "")
			)
			(fill
				(thermal_gap 0.5)
				(thermal_bridge_width 0.5)
				(island_removal_mode 0)
			)
			(polygon
				(pts
					(xy 151.511 -26.162) (xy 151.511 -25.654) (xy 151.892 -25.654) (xy 151.892 -26.162)
				)
			)
		)
		(zone
			(layer "F.Cu")
			(hatch none 0.5)
			(connect_pads
				(clearance 0)
			)
			(min_thickness 0.25)
			(keepout
				(tracks allowed)
				(vias not_allowed)
				(pads allowed)
				(copperpour not_allowed)
				(footprints allowed)
			)
			(placement
				(enabled no)
				(sheetname "")
			)
			(fill
				(thermal_gap 0.5)
				(thermal_bridge_width 0.5)
				(island_removal_mode 0)
			)
			(polygon
				(pts
					(xy 151.892 -26.162) (xy 151.892 -25.654) (xy 151.511 -25.654) (xy 151.511 -26.162)
				)
			)
		)
	)
)
